(kicad_pcb
	(version 20241229)
	(generator "pcbnew")
	(generator_version "9.0")
	(general
		(thickness 1.711)
		(legacy_teardrops no)
	)
	(paper "A4")
	(title_block
		(title "Antmicro Baseboard for Jetson AGX Thor")
		(date "2026-02-18")
		(rev "1.1.0")
		(company "Antmicro Ltd")
		(comment 1 "www.antmicro.com")
		(comment 9 "footprints 514-518 of 1170")
	)
	(layers
		(0 "F.Cu" signal)
		(4 "In1.Cu" signal)
		(6 "In2.Cu" signal)
		(8 "In3.Cu" signal)
		(10 "In4.Cu" jumper)
		(12 "In5.Cu" signal)
		(14 "In6.Cu" signal)
		(16 "In7.Cu" signal)
		(18 "In8.Cu" signal)
		(2 "B.Cu" signal)
		(9 "F.Adhes" user "F.Adhesive")
		(11 "B.Adhes" user "B.Adhesive")
		(13 "F.Paste" user)
		(15 "B.Paste" user)
		(5 "F.SilkS" user "F.Silkscreen")
		(7 "B.SilkS" user "B.Silkscreen")
		(1 "F.Mask" user)
		(3 "B.Mask" user)
		(17 "Dwgs.User" user "User.Drawings")
		(19 "Cmts.User" user "User.Comments")
		(21 "Eco1.User" user "User.Eco1")
		(23 "Eco2.User" user "User.Eco2")
		(25 "Edge.Cuts" user)
		(27 "Margin" user)
		(31 "F.CrtYd" user "F.Courtyard")
		(29 "B.CrtYd" user "B.Courtyard")
		(35 "F.Fab" user)
		(33 "B.Fab" user)
	)
	(footprint "antmicro-footprints:TP_SMD_0.75mm"
		(layer "F.Cu")
		(at 215.9 98 90)
		(property "Reference" "TP45"
			(at 1.3 2.2 180)
			(layer "F.SilkS")
			(effects
				(font
					(size 0.7 0.7)
					(thickness 0.15)
				)
				(justify right top)
			)
		)
		(property "Value" "TP_0.75mm_SMD"
			(at 0 1.2 90)
			(layer "F.Fab")
			(effects
				(font
					(size 0.7 0.7)
					(thickness 0.15)
				)
				(justify left bottom)
			)
		)
		(property "Description" "SMT test point"
			(at 0 0 90)
			(layer "F.Fab")
			(hide yes)
			(effects
				(font
					(size 1.27 1.27)
					(thickness 0.15)
				)
			)
		)
		(property "MPN" ""
			(at 0 0 90)
			(unlocked yes)
			(layer "F.Fab")
			(hide yes)
			(effects
				(font
					(size 1 1)
					(thickness 0.15)
				)
			)
		)
		(property "Manufacturer" ""
			(at 0 0 90)
			(unlocked yes)
			(layer "F.Fab")
			(hide yes)
			(effects
				(font
					(size 1 1)
					(thickness 0.15)
				)
			)
		)
		(property "Author" "Antmicro"
			(at 0 0 90)
			(unlocked yes)
			(layer "F.Fab")
			(hide yes)
			(effects
				(font
					(size 1 1)
					(thickness 0.15)
				)
			)
		)
		(property "License" "Apache-2.0"
			(at 0 0 90)
			(unlocked yes)
			(layer "F.Fab")
			(hide yes)
			(effects
				(font
					(size 1 1)
					(thickness 0.15)
				)
			)
		)
		(sheetname "/Recovery USB/")
		(sheetfile "recovery_usb.kicad_sch")
		(attr exclude_from_pos_files exclude_from_bom)
		(fp_circle
			(center 0 0)
			(end 0.475 0)
			(stroke
				(width 0.05)
				(type default)
			)
			(fill no)
			(layer "F.CrtYd")
		)
		(fp_text user "${REFERENCE}"
			(at -0.4 2.7 90)
			(layer "F.Fab")
			(effects
				(font
					(size 0.7 0.7)
					(thickness 0.15)
				)
				(justify left bottom)
			)
		)
		(fp_text user "License: Apache-2.0"
			(at -0.4 5.101 90)
			(layer "F.Fab")
			(effects
				(font
					(size 0.7 0.7)
					(thickness 0.15)
				)
				(justify left bottom)
			)
		)
		(fp_text user "Author: Antmicro"
			(at -0.4 3.901 90)
			(layer "F.Fab")
			(effects
				(font
					(size 0.7 0.7)
					(thickness 0.15)
				)
				(justify left bottom)
			)
		)
		(pad "1" smd circle
			(at 0 0 90)
			(size 0.75 0.75)
			(layers "F.Cu" "F.Mask")
			(net 889 "/Recovery USB/USBC2_ID")
			(pinfunction "1")
			(pintype "passive")
		)
	)
	(footprint "antmicro-footprints:C_0805_2012Metric"
		(layer "F.Cu")
		(at 169.53 93.32 -90)
		(descr "Capacitor SMD 0805")
		(tags "capacitor SMD 0805")
		(property "Reference" "C259"
			(at 1.745 0.425 90)
			(layer "F.SilkS")
			(effects
				(font
					(size 0.7 0.7)
					(thickness 0.15)
				)
				(justify right top)
			)
		)
		(property "Value" "C_22u_25V_0805"
			(at -2.055717 1.963152 90)
			(layer "F.Fab")
			(effects
				(font
					(size 0.7 0.7)
					(thickness 0.15)
				)
				(justify right top)
			)
		)
		(property "Datasheet" "https://product.samsungsem.com/mlcc/CL21A226MAYNNN.do"
			(at 0 0 90)
			(layer "F.Fab")
			(hide yes)
			(effects
				(font
					(size 1.27 1.27)
					(thickness 0.15)
				)
			)
		)
		(property "Description" "SMT Multilayer Ceramic Capacitor, 22uF, +/-20%, 25V, X5R, 0805 [2012 Metric]"
			(at 0 0 90)
			(layer "F.Fab")
			(hide yes)
			(effects
				(font
					(size 1.27 1.27)
					(thickness 0.15)
				)
			)
		)
		(property "MPN" "CL21A226MAYNNNE"
			(at 0 0 270)
			(unlocked yes)
			(layer "F.Fab")
			(hide yes)
			(effects
				(font
					(size 1 1)
					(thickness 0.15)
				)
			)
		)
		(property "Manufacturer" "Samsung Electro-Mechanics"
			(at 0 0 270)
			(unlocked yes)
			(layer "F.Fab")
			(hide yes)
			(effects
				(font
					(size 1 1)
					(thickness 0.15)
				)
			)
		)
		(property "License" "Apache-2.0"
			(at 0 0 270)
			(unlocked yes)
			(layer "F.Fab")
			(hide yes)
			(effects
				(font
					(size 1 1)
					(thickness 0.15)
				)
			)
		)
		(property "Author" "Antmicro"
			(at 0 0 270)
			(unlocked yes)
			(layer "F.Fab")
			(hide yes)
			(effects
				(font
					(size 1 1)
					(thickness 0.15)
				)
			)
		)
		(property "Val" "22u"
			(at 0 0 270)
			(unlocked yes)
			(layer "F.Fab")
			(hide yes)
			(effects
				(font
					(size 1 1)
					(thickness 0.15)
				)
			)
		)
		(property "Voltage" "25V"
			(at 0 0 270)
			(unlocked yes)
			(layer "F.Fab")
			(hide yes)
			(effects
				(font
					(size 1 1)
					(thickness 0.15)
				)
			)
		)
		(property "Dielectric" "X5R"
			(at 0 0 270)
			(unlocked yes)
			(layer "F.Fab")
			(hide yes)
			(effects
				(font
					(size 1 1)
					(thickness 0.15)
				)
			)
		)
		(property "Public" "False"
			(at 0 0 270)
			(unlocked yes)
			(layer "F.Fab")
			(hide yes)
			(effects
				(font
					(size 1 1)
					(thickness 0.15)
				)
			)
		)
		(component_classes
			(class "DCDC_SOM")
		)
		(sheetname "/DCDC/")
		(sheetfile "dcdc.kicad_sch")
		(attr smd)
		(fp_line
			(start -0.3 0.7)
			(end 0.3 0.7)
			(stroke
				(width 0.15)
				(type solid)
			)
			(layer "F.SilkS")
		)
		(fp_line
			(start -0.3 -0.7)
			(end 0.3 -0.7)
			(stroke
				(width 0.15)
				(type solid)
			)
			(layer "F.SilkS")
		)
		(fp_rect
			(start 1.95 -0.9)
			(end -1.95 0.9)
			(stroke
				(width 0.05)
				(type default)
			)
			(fill no)
			(layer "F.CrtYd")
		)
		(fp_rect
			(start -0.95 -0.675)
			(end 0.95 0.675)
			(stroke
				(width 0.15)
				(type solid)
			)
			(fill no)
			(layer "F.Fab")
		)
		(fp_text user "License: Apache-2.0"
			(at -1.9 4.947 90)
			(layer "F.Fab")
			(effects
				(font
					(size 0.7 0.7)
					(thickness 0.15)
				)
				(justify right top)
			)
		)
		(fp_text user "Author: Antmicro"
			(at -1.9 5.947 90)
			(layer "F.Fab")
			(effects
				(font
					(size 0.7 0.7)
					(thickness 0.15)
				)
				(justify right top)
			)
		)
		(fp_text user "${REFERENCE}"
			(at -1.9 3.947 90)
			(layer "F.Fab")
			(effects
				(font
					(size 0.7 0.7)
					(thickness 0.15)
				)
				(justify right top)
			)
		)
		(pad "1" smd roundrect
			(at -1.1 0 270)
			(size 1.2 1.3)
			(layers "F.Cu" "F.Mask" "F.Paste")
			(roundrect_rratio 0.25)
			(net 1 "GND")
			(pintype "passive")
		)
		(pad "2" smd roundrect
			(at 1.1 0 270)
			(size 1.2 1.3)
			(layers "F.Cu" "F.Mask" "F.Paste")
			(roundrect_rratio 0.25)
			(net 903 "/DCDC/16V_OUT")
			(pintype "passive")
		)
	)
	(footprint "antmicro-footprints:C_0402_1005Metric"
		(layer "F.Cu")
		(at 89.1 98.8)
		(descr "Capacitor SMD 0402")
		(tags "capacitor SMD 0402")
		(property "Reference" "C341"
			(at -3.82 0.449999 0)
			(layer "F.SilkS")
			(effects
				(font
					(size 0.7 0.7)
					(thickness 0.15)
				)
				(justify left bottom)
			)
		)
		(property "Value" "C_100n_0402"
			(at -1.022927 2.155213 0)
			(layer "F.Fab")
			(effects
				(font
					(size 0.7 0.7)
					(thickness 0.15)
				)
				(justify left bottom)
			)
		)
		(property "Datasheet" "https://www.murata.com/products/productdetail?partno=GRM155R61H104KE14%23"
			(at 0 0 0)
			(layer "F.Fab")
			(hide yes)
			(effects
				(font
					(size 1.27 1.27)
					(thickness 0.15)
				)
			)
		)
		(property "Description" "SMD Multilayer Ceramic Capacitor, 0.1 µF, 50 V, 0402 [1005 Metric], ± 10%, X5R, GRM Series"
			(at 0 0 0)
			(layer "F.Fab")
			(hide yes)
			(effects
				(font
					(size 1.27 1.27)
					(thickness 0.15)
				)
			)
		)
		(property "Manufacturer" "Murata"
			(at 0 0 0)
			(unlocked yes)
			(layer "F.Fab")
			(hide yes)
			(effects
				(font
					(size 1 1)
					(thickness 0.15)
				)
			)
		)
		(property "MPN" "GRM155R61H104KE14D"
			(at 0 0 0)
			(unlocked yes)
			(layer "F.Fab")
			(hide yes)
			(effects
				(font
					(size 1 1)
					(thickness 0.15)
				)
			)
		)
		(property "Val" "100n"
			(at 0 0 0)
			(unlocked yes)
			(layer "F.Fab")
			(hide yes)
			(effects
				(font
					(size 1 1)
					(thickness 0.15)
				)
			)
		)
		(property "License" "Apache-2.0"
			(at 0 0 0)
			(unlocked yes)
			(layer "F.Fab")
			(hide yes)
			(effects
				(font
					(size 1 1)
					(thickness 0.15)
				)
			)
		)
		(property "Author" "Antmicro"
			(at 0 0 0)
			(unlocked yes)
			(layer "F.Fab")
			(hide yes)
			(effects
				(font
					(size 1 1)
					(thickness 0.15)
				)
			)
		)
		(property "Voltage" "50V"
			(at 0 0 0)
			(unlocked yes)
			(layer "F.Fab")
			(hide yes)
			(effects
				(font
					(size 1 1)
					(thickness 0.15)
				)
			)
		)
		(property "Dielectric" "X5R"
			(at 0 0 0)
			(unlocked yes)
			(layer "F.Fab")
			(hide yes)
			(effects
				(font
					(size 1 1)
					(thickness 0.15)
				)
			)
		)
		(sheetname "/SoM_IO2/")
		(sheetfile "som_io2.kicad_sch")
		(attr smd)
		(fp_poly
			(pts
				(xy -0.925 -0.47) (xy 0.925 -0.47) (xy 0.925 0.47) (xy -0.925 0.47)
			)
			(stroke
				(width 0.05)
				(type default)
			)
			(fill no)
			(layer "F.CrtYd")
		)
		(fp_line
			(start -0.494 -0.25)
			(end 0.504 -0.25)
			(stroke
				(width 0.15)
				(type solid)
			)
			(layer "F.Fab")
		)
		(fp_line
			(start -0.494 0.248)
			(end -0.494 -0.25)
			(stroke
				(width 0.15)
				(type solid)
			)
			(layer "F.Fab")
		)
		(fp_line
			(start 0.504 -0.25)
			(end 0.504 0.248)
			(stroke
				(width 0.15)
				(type solid)
			)
			(layer "F.Fab")
		)
		(fp_line
			(start 0.504 0.248)
			(end -0.494 0.248)
			(stroke
				(width 0.15)
				(type solid)
			)
			(layer "F.Fab")
		)
		(fp_text user "License: Apache-2.0"
			(at -0.939 5.799 0)
			(layer "F.Fab")
			(effects
				(font
					(size 0.7 0.7)
					(thickness 0.15)
				)
				(justify left bottom)
			)
		)
		(fp_text user "Author: Antmicro"
			(at -0.939 3.399 0)
			(layer "F.Fab")
			(effects
				(font
					(size 0.7 0.7)
					(thickness 0.15)
				)
				(justify left bottom)
			)
		)
		(fp_text user "${REFERENCE}"
			(at -0.939 4.599 0)
			(layer "F.Fab")
			(effects
				(font
					(size 0.7 0.7)
					(thickness 0.15)
				)
				(justify left bottom)
			)
		)
		(pad "1" smd roundrect
			(at -0.48 0)
			(size 0.59 0.64)
			(layers "F.Cu" "F.Mask" "F.Paste")
			(roundrect_rratio 0.25)
			(net 631 "/Expansion connector/DP2.TX3-")
			(pintype "passive")
		)
		(pad "2" smd roundrect
			(at 0.48 0)
			(size 0.59 0.64)
			(layers "F.Cu" "F.Mask" "F.Paste")
			(roundrect_rratio 0.25)
			(net 1261 "/SoM_IO2/DP2.TX3_C-")
			(pintype "passive")
		)
	)
	(footprint "antmicro-footprints:R_0402_1005Metric"
		(layer "F.Cu")
		(at 187.25 57.25 -90)
		(descr "Resistor SMD 0402")
		(tags "resistor SMD 0402")
		(property "Reference" "R237"
			(at -1.45 1.35 90)
			(layer "F.SilkS")
			(effects
				(font
					(size 0.7 0.7)
					(thickness 0.15)
				)
				(justify right top)
			)
		)
		(property "Value" "R_10k_0402"
			(at -1.011843 1.772047 90)
			(layer "F.Fab")
			(effects
				(font
					(size 0.7 0.7)
					(thickness 0.15)
				)
				(justify right top)
			)
		)
		(property "Datasheet" "https://www.bourns.com/docs/product-datasheets/cr.pdf"
			(at 0 0 90)
			(layer "F.Fab")
			(hide yes)
			(effects
				(font
					(size 1.27 1.27)
					(thickness 0.15)
				)
			)
		)
		(property "Description" "SMD Chip Resistor, 10 kohm, ± 1%, 62.5 mW, 0402 [1005 Metric], Thick Film, General Purpose"
			(at 0 0 90)
			(layer "F.Fab")
			(hide yes)
			(effects
				(font
					(size 1.27 1.27)
					(thickness 0.15)
				)
			)
		)
		(property "Manufacturer" "Bourns"
			(at 0 0 270)
			(unlocked yes)
			(layer "F.Fab")
			(hide yes)
			(effects
				(font
					(size 1 1)
					(thickness 0.15)
				)
			)
		)
		(property "MPN" "CR0402-FX-1002GLF"
			(at 0 0 270)
			(unlocked yes)
			(layer "F.Fab")
			(hide yes)
			(effects
				(font
					(size 1 1)
					(thickness 0.15)
				)
			)
		)
		(property "Val" "10k"
			(at 0 0 270)
			(unlocked yes)
			(layer "F.Fab")
			(hide yes)
			(effects
				(font
					(size 1 1)
					(thickness 0.15)
				)
			)
		)
		(property "License" "Apache-2.0"
			(at 0 0 270)
			(unlocked yes)
			(layer "F.Fab")
			(hide yes)
			(effects
				(font
					(size 1 1)
					(thickness 0.15)
				)
			)
		)
		(property "Author" "Antmicro"
			(at 0 0 270)
			(unlocked yes)
			(layer "F.Fab")
			(hide yes)
			(effects
				(font
					(size 1 1)
					(thickness 0.15)
				)
			)
		)
		(property "Tolerance" "1%"
			(at 0 0 270)
			(unlocked yes)
			(layer "F.Fab")
			(hide yes)
			(effects
				(font
					(size 1 1)
					(thickness 0.15)
				)
			)
		)
		(sheetname "/Peripherals/")
		(sheetfile "peripherals.kicad_sch")
		(attr smd)
		(fp_rect
			(start -0.925 -0.47)
			(end 0.925 0.47)
			(stroke
				(width 0.05)
				(type default)
			)
			(fill no)
			(layer "F.CrtYd")
		)
		(fp_rect
			(start -0.5 -0.25)
			(end 0.5 0.25)
			(stroke
				(width 0.15)
				(type solid)
			)
			(fill no)
			(layer "F.Fab")
		)
		(fp_text user "Author: Antmicro"
			(at -0.95 4.169 90)
			(layer "F.Fab")
			(effects
				(font
					(size 0.7 0.7)
					(thickness 0.15)
				)
				(justify right top)
			)
		)
		(fp_text user "License: Apache-2.0"
			(at -0.95 5.169 90)
			(layer "F.Fab")
			(effects
				(font
					(size 0.7 0.7)
					(thickness 0.15)
				)
				(justify right top)
			)
		)
		(fp_text user "${REFERENCE}"
			(at -0.95 3.168 90)
			(layer "F.Fab")
			(effects
				(font
					(size 0.7 0.7)
					(thickness 0.15)
				)
				(justify right top)
			)
		)
		(pad "1" smd roundrect
			(at -0.48 0 270)
			(size 0.59 0.64)
			(layers "F.Cu" "F.Mask" "F.Paste")
			(roundrect_rratio 0.25)
			(net 448 "/Expansion connector/GPIO.USER_BTN0")
			(pintype "passive")
		)
		(pad "2" smd roundrect
			(at 0.48 0 270)
			(size 0.59 0.64)
			(layers "F.Cu" "F.Mask" "F.Paste")
			(roundrect_rratio 0.25)
			(net 11 "+1V8")
			(pintype "passive")
		)
	)
	(footprint "antmicro-footprints:R_0402_1005Metric"
		(layer "F.Cu")
		(at 95.9 58.38 90)
		(descr "Resistor SMD 0402")
		(tags "resistor SMD 0402")
		(property "Reference" "R408"
			(at -3.67 0.35 90)
			(layer "F.SilkS")
			(effects
				(font
					(size 0.7 0.7)
					(thickness 0.15)
				)
				(justify left bottom)
			)
		)
		(property "Value" "R_124k_0402"
			(at -1.011843 1.772047 90)
			(layer "F.Fab")
			(effects
				(font
					(size 0.7 0.7)
					(thickness 0.15)
				)
				(justify left bottom)
			)
		)
		(property "Datasheet" "https://www.bourns.com/docs/product-datasheets/cr.pdf"
			(at 0 0 90)
			(layer "F.Fab")
			(hide yes)
			(effects
				(font
					(size 1.27 1.27)
					(thickness 0.15)
				)
			)
		)
		(property "Description" "SMD Chip Resistor, 124 kohm, ± 1%, 100 mW, 0402 [1005 Metric], Thick Film, Precision"
			(at 0 0 90)
			(layer "F.Fab")
			(hide yes)
			(effects
				(font
					(size 1.27 1.27)
					(thickness 0.15)
				)
			)
		)
		(property "MPN" "CR0402-FX-1243GLF"
			(at 0 0 90)
			(unlocked yes)
			(layer "F.Fab")
			(hide yes)
			(effects
				(font
					(size 1 1)
					(thickness 0.15)
				)
			)
		)
		(property "Manufacturer" "Bourns"
			(at 0 0 90)
			(unlocked yes)
			(layer "F.Fab")
			(hide yes)
			(effects
				(font
					(size 1 1)
					(thickness 0.15)
				)
			)
		)
		(property "License" "Apache-2.0"
			(at 0 0 90)
			(unlocked yes)
			(layer "F.Fab")
			(hide yes)
			(effects
				(font
					(size 1 1)
					(thickness 0.15)
				)
			)
		)
		(property "Author" "Antmicro"
			(at 0 0 90)
			(unlocked yes)
			(layer "F.Fab")
			(hide yes)
			(effects
				(font
					(size 1 1)
					(thickness 0.15)
				)
			)
		)
		(property "Val" "124k"
			(at 0 0 90)
			(unlocked yes)
			(layer "F.Fab")
			(hide yes)
			(effects
				(font
					(size 1 1)
					(thickness 0.15)
				)
			)
		)
		(property "Tolerance" "1%"
			(at 0 0 90)
			(unlocked yes)
			(layer "F.Fab")
			(hide yes)
			(effects
				(font
					(size 1 1)
					(thickness 0.15)
				)
			)
		)
		(sheetname "/SoM_Power/")
		(sheetfile "som_power.kicad_sch")
		(attr smd)
		(fp_rect
			(start -0.925 -0.47)
			(end 0.925 0.47)
			(stroke
				(width 0.05)
				(type default)
			)
			(fill no)
			(layer "F.CrtYd")
		)
		(fp_rect
			(start -0.5 -0.25)
			(end 0.5 0.25)
			(stroke
				(width 0.15)
				(type solid)
			)
			(fill no)
			(layer "F.Fab")
		)
		(fp_text user "Author: Antmicro"
			(at -0.95 4.169 90)
			(layer "F.Fab")
			(effects
				(font
					(size 0.7 0.7)
					(thickness 0.15)
				)
				(justify left bottom)
			)
		)
		(fp_text user "${REFERENCE}"
			(at -0.95 3.168 90)
			(layer "F.Fab")
			(effects
				(font
					(size 0.7 0.7)
					(thickness 0.15)
				)
				(justify left bottom)
			)
		)
		(fp_text user "License: Apache-2.0"
			(at -0.95 5.169 90)
			(layer "F.Fab")
			(effects
				(font
					(size 0.7 0.7)
					(thickness 0.15)
				)
				(justify left bottom)
			)
		)
		(pad "1" smd roundrect
			(at -0.48 0 90)
			(size 0.59 0.64)
			(layers "F.Cu" "F.Mask" "F.Paste")
			(roundrect_rratio 0.25)
			(net 1 "GND")
			(pintype "passive")
		)
		(pad "2" smd roundrect
			(at 0.48 0 90)
			(size 0.59 0.64)
			(layers "F.Cu" "F.Mask" "F.Paste")
			(roundrect_rratio 0.25)
			(net 1381 "Net-(U3-SET)")
			(pintype "passive")
		)
	)
)
